(kicad_pcb
	(version 20241229)
	(generator "pcbnew")
	(generator_version "9.0")
	(general
		(thickness 1.61)
		(legacy_teardrops no)
	)
	(paper "A3")
	(title_block
		(title "RDIMM DDR5 Tester")
		(date "2026-05-21")
		(rev "2.2.0")
		(company "Antmicro")
		(comment 9 "footprints 450-454 of 796")
	)
	(layers
		(0 "F.Cu" signal)
		(4 "In1.Cu" power)
		(6 "In2.Cu" mixed)
		(8 "In3.Cu" power)
		(10 "In4.Cu" mixed)
		(12 "In5.Cu" power)
		(14 "In6.Cu" mixed)
		(16 "In7.Cu" power)
		(18 "In8.Cu" power)
		(20 "In9.Cu" mixed)
		(22 "In10.Cu" power)
		(2 "B.Cu" signal)
		(9 "F.Adhes" user "F.Adhesive")
		(11 "B.Adhes" user "B.Adhesive")
		(13 "F.Paste" user)
		(15 "B.Paste" user)
		(5 "F.SilkS" user "F.Silkscreen")
		(7 "B.SilkS" user "B.Silkscreen")
		(1 "F.Mask" user)
		(3 "B.Mask" user)
		(17 "Dwgs.User" user "User.Drawings")
		(19 "Cmts.User" user "User.Comments")
		(21 "Eco1.User" user "User.Eco1")
		(23 "Eco2.User" user "User.Eco2")
		(25 "Edge.Cuts" user)
		(27 "Margin" user)
		(31 "F.CrtYd" user "F.Courtyard")
		(29 "B.CrtYd" user "B.Courtyard")
		(35 "F.Fab" user)
		(33 "B.Fab" user)
	)
	(footprint "antmicro-footprints:C_0402_1005Metric_EIA"
		(layer "B.Cu")
		(at 199 149.5 -90)
		(descr "Capacitor SMD 0402 (1005 Metric), square (rectangular) end terminal, IPC_7351 nominal, (Body size source: IPC-SM-782 page 76, https://www.pcb-3d.com/wordpress/wp-content/uploads/ipc-sm-782a_amendment_1_and_2.pdf)")
		(tags "capacitor 0402")
		(property "Reference" "C95"
			(at 0.95 -0.425 90)
			(layer "B.SilkS")
			(effects
				(font
					(size 0.7 0.7)
					(thickness 0.15)
				)
				(justify left bottom mirror)
			)
		)
		(property "Value" "C_10u_10V_0402"
			(at 0 -1.169 90)
			(layer "B.Fab")
			(effects
				(font
					(size 0.7 0.7)
					(thickness 0.15)
				)
				(justify left bottom mirror)
			)
		)
		(property "Datasheet" "https://www.murata.com/products/productdetail?partno=GRM155R61A106ME11%23"
			(at 0 0 270)
			(layer "F.Fab")
			(hide yes)
			(effects
				(font
					(size 1.27 1.27)
					(thickness 0.15)
				)
			)
		)
		(property "MPN" "GRM155R61A106ME11D"
			(at 0 0 270)
			(unlocked yes)
			(layer "B.Fab")
			(hide yes)
			(effects
				(font
					(size 1 1)
					(thickness 0.15)
				)
				(justify mirror)
			)
		)
		(property "Manufacturer" "Murata"
			(at 0 0 270)
			(unlocked yes)
			(layer "B.Fab")
			(hide yes)
			(effects
				(font
					(size 1 1)
					(thickness 0.15)
				)
				(justify mirror)
			)
		)
		(property "License" "Apache-2.0"
			(at 0 0 270)
			(unlocked yes)
			(layer "B.Fab")
			(hide yes)
			(effects
				(font
					(size 1 1)
					(thickness 0.15)
				)
				(justify mirror)
			)
		)
		(property "Author" "Antmicro"
			(at 0 0 270)
			(unlocked yes)
			(layer "B.Fab")
			(hide yes)
			(effects
				(font
					(size 1 1)
					(thickness 0.15)
				)
				(justify mirror)
			)
		)
		(property "Val" "10u"
			(at 0 0 270)
			(unlocked yes)
			(layer "B.Fab")
			(hide yes)
			(effects
				(font
					(size 1 1)
					(thickness 0.15)
				)
				(justify mirror)
			)
		)
		(property "Voltage" "10V"
			(at 0 0 270)
			(unlocked yes)
			(layer "B.Fab")
			(hide yes)
			(effects
				(font
					(size 1 1)
					(thickness 0.15)
				)
				(justify mirror)
			)
		)
		(property "Dielectric" "X5R"
			(at 0 0 270)
			(unlocked yes)
			(layer "B.Fab")
			(hide yes)
			(effects
				(font
					(size 1 1)
					(thickness 0.15)
				)
				(justify mirror)
			)
		)
		(sheetname "/FPGA power/")
		(sheetfile "fpga-power.kicad_sch")
		(attr smd)
		(fp_rect
			(start -0.95 0.45)
			(end 0.95 -0.45)
			(stroke
				(width 0.05)
				(type default)
			)
			(fill no)
			(layer "B.CrtYd")
		)
		(fp_line
			(start -0.5 0.25)
			(end 0.498 0.25)
			(stroke
				(width 0.15)
				(type solid)
			)
			(layer "B.Fab")
		)
		(fp_line
			(start 0.498 0.25)
			(end 0.498 -0.248)
			(stroke
				(width 0.15)
				(type solid)
			)
			(layer "B.Fab")
		)
		(fp_line
			(start -0.5 -0.248)
			(end -0.5 0.25)
			(stroke
				(width 0.15)
				(type solid)
			)
			(layer "B.Fab")
		)
		(fp_line
			(start 0.498 -0.248)
			(end -0.5 -0.248)
			(stroke
				(width 0.15)
				(type solid)
			)
			(layer "B.Fab")
		)
		(fp_text user "${REFERENCE}"
			(at -0.9656 -3.169 90)
			(layer "B.Fab")
			(effects
				(font
					(size 0.7 0.7)
					(thickness 0.15)
				)
				(justify left bottom mirror)
			)
		)
		(fp_text user "Author: Antmicro"
			(at -0.9656 -5.569 90)
			(layer "B.Fab")
			(effects
				(font
					(size 0.7 0.7)
					(thickness 0.15)
				)
				(justify left bottom mirror)
			)
		)
		(fp_text user "License: Apache-2.0"
			(at -0.9656 -4.369 90)
			(layer "B.Fab")
			(effects
				(font
					(size 0.7 0.7)
					(thickness 0.15)
				)
				(justify left bottom mirror)
			)
		)
		(pad "1" smd roundrect
			(at -0.5 0 180)
			(size 0.6 0.6)
			(layers "B.Cu" "B.Mask" "B.Paste")
			(roundrect_rratio 0.25)
			(net 1 "GND")
			(pintype "passive")
		)
		(pad "2" smd roundrect
			(at 0.498 0 270)
			(size 0.6 0.6)
			(layers "B.Cu" "B.Mask" "B.Paste")
			(roundrect_rratio 0.25)
			(net 151 "+3V3")
			(pintype "passive")
		)
	)
	(footprint "antmicro-footprints:R_0402_1005Metric"
		(layer "B.Cu")
		(at 156.124499 190.274 180)
		(descr "Resistor SMD 0402")
		(tags "resistor SMD 0402")
		(property "Reference" "R192"
			(at 1.004499 -0.376 0)
			(layer "B.SilkS")
			(effects
				(font
					(size 0.7 0.7)
					(thickness 0.15)
				)
				(justify left bottom mirror)
			)
		)
		(property "Value" "R_10k_0402"
			(at -1.011843 -1.772047 0)
			(layer "B.Fab")
			(effects
				(font
					(size 0.7 0.7)
					(thickness 0.15)
				)
				(justify left bottom mirror)
			)
		)
		(property "Datasheet" "https://www.bourns.com/docs/product-datasheets/cr.pdf"
			(at 0 0 180)
			(layer "F.Fab")
			(hide yes)
			(effects
				(font
					(size 1.27 1.27)
					(thickness 0.15)
				)
			)
		)
		(property "MPN" "CR0402-FX-1002GLF"
			(at 0 0 180)
			(unlocked yes)
			(layer "B.Fab")
			(hide yes)
			(effects
				(font
					(size 1 1)
					(thickness 0.15)
				)
				(justify mirror)
			)
		)
		(property "Manufacturer" "Bourns"
			(at 0 0 180)
			(unlocked yes)
			(layer "B.Fab")
			(hide yes)
			(effects
				(font
					(size 1 1)
					(thickness 0.15)
				)
				(justify mirror)
			)
		)
		(property "License" "Apache-2.0"
			(at 0 0 180)
			(unlocked yes)
			(layer "B.Fab")
			(hide yes)
			(effects
				(font
					(size 1 1)
					(thickness 0.15)
				)
				(justify mirror)
			)
		)
		(property "Author" "Antmicro"
			(at 0 0 180)
			(unlocked yes)
			(layer "B.Fab")
			(hide yes)
			(effects
				(font
					(size 1 1)
					(thickness 0.15)
				)
				(justify mirror)
			)
		)
		(property "Val" "10k"
			(at 0 0 180)
			(unlocked yes)
			(layer "B.Fab")
			(hide yes)
			(effects
				(font
					(size 1 1)
					(thickness 0.15)
				)
				(justify mirror)
			)
		)
		(property "Tolerance" "1%"
			(at 0 0 180)
			(unlocked yes)
			(layer "B.Fab")
			(hide yes)
			(effects
				(font
					(size 1 1)
					(thickness 0.15)
				)
				(justify mirror)
			)
		)
		(sheetname "/PCIe connector/")
		(sheetfile "pcie-connector.kicad_sch")
		(attr smd exclude_from_bom dnp)
		(fp_rect
			(start -0.925 0.47)
			(end 0.925 -0.47)
			(stroke
				(width 0.05)
				(type default)
			)
			(fill no)
			(layer "B.CrtYd")
		)
		(fp_rect
			(start -0.5 0.25)
			(end 0.5 -0.25)
			(stroke
				(width 0.15)
				(type solid)
			)
			(fill no)
			(layer "B.Fab")
		)
		(fp_text user "${REFERENCE}"
			(at -0.95 -3.168 0)
			(layer "B.Fab")
			(effects
				(font
					(size 0.7 0.7)
					(thickness 0.15)
				)
				(justify left bottom mirror)
			)
		)
		(fp_text user "Author: Antmicro"
			(at -0.95 -4.169 0)
			(layer "B.Fab")
			(effects
				(font
					(size 0.7 0.7)
					(thickness 0.15)
				)
				(justify left bottom mirror)
			)
		)
		(fp_text user "License: Apache-2.0"
			(at -0.95 -5.169 0)
			(layer "B.Fab")
			(effects
				(font
					(size 0.7 0.7)
					(thickness 0.15)
				)
				(justify left bottom mirror)
			)
		)
		(pad "1" smd roundrect
			(at -0.48 0 180)
			(size 0.59 0.64)
			(layers "B.Cu" "B.Mask" "B.Paste")
			(roundrect_rratio 0.25)
			(net 1 "GND")
			(pintype "passive")
		)
		(pad "2" smd roundrect
			(at 0.48 0 180)
			(size 0.59 0.64)
			(layers "B.Cu" "B.Mask" "B.Paste")
			(roundrect_rratio 0.25)
			(net 98 "PCIE.PWRGD")
			(pintype "passive")
		)
	)
	(footprint "antmicro-footprints:C_0603_1608Metric"
		(layer "B.Cu")
		(at 231.534998 172.080002 90)
		(descr "Capacitor SMD 0603")
		(tags "capacitor 0603")
		(property "Reference" "C268"
			(at -4.069998 0.320001 90)
			(layer "B.SilkS")
			(effects
				(font
					(size 0.7 0.7)
					(thickness 0.15)
				)
				(justify right bottom mirror)
			)
		)
		(property "Value" "C_22u_0603"
			(at -1.42757 -1.770288 90)
			(layer "B.Fab")
			(effects
				(font
					(size 0.7 0.7)
					(thickness 0.15)
				)
				(justify right bottom mirror)
			)
		)
		(property "Datasheet" "https://www.murata.com/products/productdetail?partno=GRM188R60J226MEA0%23"
			(at 0 0 90)
			(layer "F.Fab")
			(hide yes)
			(effects
				(font
					(size 1.27 1.27)
					(thickness 0.15)
				)
			)
		)
		(property "Manufacturer" "Murata"
			(at 0 0 90)
			(unlocked yes)
			(layer "B.Fab")
			(hide yes)
			(effects
				(font
					(size 1 1)
					(thickness 0.15)
				)
				(justify mirror)
			)
		)
		(property "MPN" "GRM188R60J226MEA0D"
			(at 0 0 90)
			(unlocked yes)
			(layer "B.Fab")
			(hide yes)
			(effects
				(font
					(size 1 1)
					(thickness 0.15)
				)
				(justify mirror)
			)
		)
		(property "Val" "22u"
			(at 0 0 90)
			(unlocked yes)
			(layer "B.Fab")
			(hide yes)
			(effects
				(font
					(size 1 1)
					(thickness 0.15)
				)
				(justify mirror)
			)
		)
		(property "License" "Apache-2.0"
			(at 0 0 90)
			(unlocked yes)
			(layer "B.Fab")
			(hide yes)
			(effects
				(font
					(size 1 1)
					(thickness 0.15)
				)
				(justify mirror)
			)
		)
		(property "Author" "Antmicro"
			(at 0 0 90)
			(unlocked yes)
			(layer "B.Fab")
			(hide yes)
			(effects
				(font
					(size 1 1)
					(thickness 0.15)
				)
				(justify mirror)
			)
		)
		(property "Voltage" ""
			(at 0 0 90)
			(unlocked yes)
			(layer "B.Fab")
			(hide yes)
			(effects
				(font
					(size 1 1)
					(thickness 0.15)
				)
				(justify mirror)
			)
		)
		(property "Dielectric" ""
			(at 0 0 90)
			(unlocked yes)
			(layer "B.Fab")
			(hide yes)
			(effects
				(font
					(size 1 1)
					(thickness 0.15)
				)
				(justify mirror)
			)
		)
		(sheetname "/Supply/DC-DC VCCINT/")
		(sheetfile "dc-dc-vccint.kicad_sch")
		(attr smd)
		(fp_line
			(start -0.15 -0.4)
			(end 0.15 -0.4)
			(stroke
				(width 0.15)
				(type solid)
			)
			(layer "B.SilkS")
		)
		(fp_line
			(start -0.15 0.4)
			(end 0.15 0.4)
			(stroke
				(width 0.15)
				(type solid)
			)
			(layer "B.SilkS")
		)
		(fp_rect
			(start -1.25 0.65)
			(end 1.25 -0.65)
			(stroke
				(width 0.05)
				(type solid)
			)
			(fill no)
			(layer "B.CrtYd")
		)
		(fp_rect
			(start -0.8 0.4)
			(end 0.8 -0.4)
			(stroke
				(width 0.15)
				(type solid)
			)
			(fill no)
			(layer "B.Fab")
		)
		(fp_text user "License: Apache-2.0"
			(at -1.682 -5.895 270)
			(layer "B.Fab")
			(effects
				(font
					(size 0.7 0.7)
					(thickness 0.15)
				)
				(justify left bottom mirror)
			)
		)
		(fp_text user "Author: Antmicro"
			(at -1.682 -4.894 270)
			(layer "B.Fab")
			(effects
				(font
					(size 0.7 0.7)
					(thickness 0.15)
				)
				(justify left bottom mirror)
			)
		)
		(fp_text user "${REFERENCE}"
			(at -1.682 -3.895 270)
			(layer "B.Fab")
			(effects
				(font
					(size 0.7 0.7)
					(thickness 0.15)
				)
				(justify left bottom mirror)
			)
		)
		(pad "1" smd roundrect
			(at -0.7 0 90)
			(size 0.8 1)
			(layers "B.Cu" "B.Mask" "B.Paste")
			(roundrect_rratio 0.2)
			(net 1 "GND")
			(pintype "passive")
		)
		(pad "2" smd roundrect
			(at 0.7 0 90)
			(size 0.8 1)
			(layers "B.Cu" "B.Mask" "B.Paste")
			(roundrect_rratio 0.2)
			(net 224 "/Supply/DC-DC VCCINT/0V85_REG1")
			(pintype "passive")
		)
	)
	(footprint "antmicro-footprints:R_0402_1005Metric"
		(layer "B.Cu")
		(at 254.324499 160.174)
		(descr "Resistor SMD 0402")
		(tags "resistor SMD 0402")
		(property "Reference" "R156"
			(at 0.925501 0.525 0)
			(layer "B.SilkS")
			(effects
				(font
					(size 0.7 0.7)
					(thickness 0.15)
				)
				(justify right bottom mirror)
			)
		)
		(property "Value" "R_0R_0402"
			(at -1.011843 -1.772047 0)
			(layer "B.Fab")
			(effects
				(font
					(size 0.7 0.7)
					(thickness 0.15)
				)
				(justify right bottom mirror)
			)
		)
		(property "Datasheet" "https://industrial.panasonic.com/cdbs/www-data/pdf/RDA0000/AOA0000C301.pdf"
			(at 0 0 0)
			(layer "F.Fab")
			(hide yes)
			(effects
				(font
					(size 1.27 1.27)
					(thickness 0.15)
				)
			)
		)
		(property "Manufacturer" "Panasonic"
			(at 0 0 0)
			(unlocked yes)
			(layer "B.Fab")
			(hide yes)
			(effects
				(font
					(size 1 1)
					(thickness 0.15)
				)
				(justify mirror)
			)
		)
		(property "MPN" "ERJ2GE0R00X"
			(at 0 0 0)
			(unlocked yes)
			(layer "B.Fab")
			(hide yes)
			(effects
				(font
					(size 1 1)
					(thickness 0.15)
				)
				(justify mirror)
			)
		)
		(property "Val" "0R"
			(at 0 0 0)
			(unlocked yes)
			(layer "B.Fab")
			(hide yes)
			(effects
				(font
					(size 1 1)
					(thickness 0.15)
				)
				(justify mirror)
			)
		)
		(property "License" "Apache-2.0"
			(at 0 0 0)
			(unlocked yes)
			(layer "B.Fab")
			(hide yes)
			(effects
				(font
					(size 1 1)
					(thickness 0.15)
				)
				(justify mirror)
			)
		)
		(property "Author" "Antmicro"
			(at 0 0 0)
			(unlocked yes)
			(layer "B.Fab")
			(hide yes)
			(effects
				(font
					(size 1 1)
					(thickness 0.15)
				)
				(justify mirror)
			)
		)
		(property "Tolerance" "~"
			(at 0 0 0)
			(unlocked yes)
			(layer "B.Fab")
			(hide yes)
			(effects
				(font
					(size 1 1)
					(thickness 0.15)
				)
				(justify mirror)
			)
		)
		(property "Current" "1A"
			(at 0 0 0)
			(unlocked yes)
			(layer "B.Fab")
			(hide yes)
			(effects
				(font
					(size 1 1)
					(thickness 0.15)
				)
				(justify mirror)
			)
		)
		(sheetname "/Supply/DC-DC IO/")
		(sheetfile "dc-dc-io.kicad_sch")
		(attr smd exclude_from_bom dnp)
		(fp_rect
			(start -0.925 0.47)
			(end 0.925 -0.47)
			(stroke
				(width 0.05)
				(type default)
			)
			(fill no)
			(layer "B.CrtYd")
		)
		(fp_rect
			(start -0.5 0.25)
			(end 0.5 -0.25)
			(stroke
				(width 0.15)
				(type solid)
			)
			(fill no)
			(layer "B.Fab")
		)
		(fp_text user "Author: Antmicro"
			(at -0.95 -4.169 180)
			(layer "B.Fab")
			(effects
				(font
					(size 0.7 0.7)
					(thickness 0.15)
				)
				(justify left bottom mirror)
			)
		)
		(fp_text user "License: Apache-2.0"
			(at -0.95 -5.169 180)
			(layer "B.Fab")
			(effects
				(font
					(size 0.7 0.7)
					(thickness 0.15)
				)
				(justify left bottom mirror)
			)
		)
		(fp_text user "${REFERENCE}"
			(at -0.95 -3.168 180)
			(layer "B.Fab")
			(effects
				(font
					(size 0.7 0.7)
					(thickness 0.15)
				)
				(justify left bottom mirror)
			)
		)
		(pad "1" smd roundrect
			(at -0.48 0)
			(size 0.59 0.64)
			(layers "B.Cu" "B.Mask" "B.Paste")
			(roundrect_rratio 0.25)
			(net 1 "GND")
			(pintype "passive")
		)
		(pad "2" smd roundrect
			(at 0.48 0)
			(size 0.59 0.64)
			(layers "B.Cu" "B.Mask" "B.Paste")
			(roundrect_rratio 0.25)
			(net 714 "/Supply/DC-DC IO/FB5")
			(pintype "passive")
		)
	)
	(footprint "antmicro-footprints:C_0402_1005Metric"
		(layer "B.Cu")
		(at 189.622499 193.2285 90)
		(descr "Capacitor SMD 0402")
		(tags "capacitor SMD 0402")
		(property "Reference" "C253"
			(at 0.994 0.403501 90)
			(layer "B.SilkS")
			(effects
				(font
					(size 0.7 0.7)
					(thickness 0.15)
				)
				(justify right bottom mirror)
			)
		)
		(property "Value" "C_100n_0402"
			(at -1.022927 -2.155213 90)
			(layer "B.Fab")
			(effects
				(font
					(size 0.7 0.7)
					(thickness 0.15)
				)
				(justify right bottom mirror)
			)
		)
		(property "Datasheet" "https://www.murata.com/products/productdetail?partno=GRM155R61H104KE14%23"
			(at 0 0 90)
			(layer "F.Fab")
			(hide yes)
			(effects
				(font
					(size 1.27 1.27)
					(thickness 0.15)
				)
			)
		)
		(property "Manufacturer" "Murata"
			(at 0 0 90)
			(unlocked yes)
			(layer "B.Fab")
			(hide yes)
			(effects
				(font
					(size 1 1)
					(thickness 0.15)
				)
				(justify mirror)
			)
		)
		(property "MPN" "GRM155R61H104KE14D"
			(at 0 0 90)
			(unlocked yes)
			(layer "B.Fab")
			(hide yes)
			(effects
				(font
					(size 1 1)
					(thickness 0.15)
				)
				(justify mirror)
			)
		)
		(property "Val" "100n"
			(at 0 0 90)
			(unlocked yes)
			(layer "B.Fab")
			(hide yes)
			(effects
				(font
					(size 1 1)
					(thickness 0.15)
				)
				(justify mirror)
			)
		)
		(property "License" "Apache-2.0"
			(at 0 0 90)
			(unlocked yes)
			(layer "B.Fab")
			(hide yes)
			(effects
				(font
					(size 1 1)
					(thickness 0.15)
				)
				(justify mirror)
			)
		)
		(property "Author" "Antmicro"
			(at 0 0 90)
			(unlocked yes)
			(layer "B.Fab")
			(hide yes)
			(effects
				(font
					(size 1 1)
					(thickness 0.15)
				)
				(justify mirror)
			)
		)
		(property "Voltage" "50V"
			(at 0 0 90)
			(unlocked yes)
			(layer "B.Fab")
			(hide yes)
			(effects
				(font
					(size 1 1)
					(thickness 0.15)
				)
				(justify mirror)
			)
		)
		(property "Dielectric" "X5R"
			(at 0 0 90)
			(unlocked yes)
			(layer "B.Fab")
			(hide yes)
			(effects
				(font
					(size 1 1)
					(thickness 0.15)
				)
				(justify mirror)
			)
		)
		(sheetname "/FPGA MGT Interface/")
		(sheetfile "fpga-mgt.kicad_sch")
		(attr smd)
		(fp_rect
			(start -0.925 0.47)
			(end 0.925 -0.47)
			(stroke
				(width 0.05)
				(type default)
			)
			(fill no)
			(layer "B.CrtYd")
		)
		(fp_line
			(start 0.504 -0.248)
			(end -0.494 -0.248)
			(stroke
				(width 0.15)
				(type solid)
			)
			(layer "B.Fab")
		)
		(fp_line
			(start -0.494 -0.248)
			(end -0.494 0.25)
			(stroke
				(width 0.15)
				(type solid)
			)
			(layer "B.Fab")
		)
		(fp_line
			(start 0.504 0.25)
			(end 0.504 -0.248)
			(stroke
				(width 0.15)
				(type solid)
			)
			(layer "B.Fab")
		)
		(fp_line
			(start -0.494 0.25)
			(end 0.504 0.25)
			(stroke
				(width 0.15)
				(type solid)
			)
			(layer "B.Fab")
		)
		(fp_text user "Author: Antmicro"
			(at -0.939 -3.399 270)
			(layer "B.Fab")
			(effects
				(font
					(size 0.7 0.7)
					(thickness 0.15)
				)
				(justify left bottom mirror)
			)
		)
		(fp_text user "${REFERENCE}"
			(at -0.939 -4.599 270)
			(layer "B.Fab")
			(effects
				(font
					(size 0.7 0.7)
					(thickness 0.15)
				)
				(justify left bottom mirror)
			)
		)
		(fp_text user "License: Apache-2.0"
			(at -0.939 -5.799 270)
			(layer "B.Fab")
			(effects
				(font
					(size 0.7 0.7)
					(thickness 0.15)
				)
				(justify left bottom mirror)
			)
		)
		(pad "1" smd roundrect
			(at -0.48 0 90)
			(size 0.59 0.64)
			(layers "B.Cu" "B.Mask" "B.Paste")
			(roundrect_rratio 0.25)
			(net 255 "/FPGA MGT Interface/PCIE.TXD6_P")
			(pintype "passive")
		)
		(pad "2" smd roundrect
			(at 0.48 0 90)
			(size 0.59 0.64)
			(layers "B.Cu" "B.Mask" "B.Paste")
			(roundrect_rratio 0.25)
			(net 559 "/FPGA MGT Interface/GTY_224_TX1_P")
			(pintype "passive")
		)
	)
)
